(kicad_pcb
	(version 20260206)
	(generator "pcbnew")
	(generator_version "10.0")
	(general
		(thickness 1.6)
		(legacy_teardrops no)
	)
	(paper "A4")
	(title_block
		(title "01162023_DA0F0TEBIF0_F0T_Expander_BD_F_brd_V02_OCP.brd")
		(comment 1 "Grand Teton / footprints 5586-5592 of 9728")
	)
	(layers
		(0 "F.Cu" signal "TOP")
		(4 "In1.Cu" signal "GND")
		(6 "In2.Cu" signal "VCC")
		(8 "In3.Cu" signal "VCC1")
		(10 "In4.Cu" signal "GND1")
		(12 "In5.Cu" signal "IN1")
		(14 "In6.Cu" signal "GND2")
		(16 "In7.Cu" signal "IN2")
		(18 "In8.Cu" signal "GND3")
		(20 "In9.Cu" signal "IN3")
		(22 "In10.Cu" signal "GND4")
		(24 "In11.Cu" signal "IN4")
		(26 "In12.Cu" signal "GND5")
		(28 "In13.Cu" signal "IN5")
		(30 "In14.Cu" signal "GND6")
		(32 "In15.Cu" signal "IN6")
		(34 "In16.Cu" signal "GND7")
		(2 "B.Cu" signal "BOTTOM")
		(9 "F.Adhes" user "F.Adhesive")
		(11 "B.Adhes" user "B.Adhesive")
		(13 "F.Paste" user "Package Geometry/Pastemask Top")
		(15 "B.Paste" user "Package Geometry/Pastemask Bottom")
		(5 "F.SilkS" user "Ref Des/Silkscreen Top")
		(7 "B.SilkS" user "Ref Des/Silkscreen Bottom")
		(1 "F.Mask" user "Board Geometry/Soldermask Top")
		(3 "B.Mask" user "Board Geometry/Soldermask Bottom")
		(17 "Dwgs.User" user "User.Drawings")
		(19 "Cmts.User" user "User.Comments")
		(21 "Eco1.User" user "User.Eco1")
		(23 "Eco2.User" user "User.Eco2")
		(25 "Edge.Cuts" user "Board Geometry/Outline")
		(27 "Margin" user)
		(31 "F.CrtYd" user "Package Geometry/Place Bound Top")
		(29 "B.CrtYd" user "Package Geometry/Place Bound Bottom")
		(35 "F.Fab" user "Ref Des/Assembly Top")
		(33 "B.Fab" user "Ref Des/Assembly Bottom")
	)
	(footprint ""
		(layer "F.Cu")
		(at 100.75672 -10.545572 90)
		(property "Reference" "R1649"
			(at 0 0 90)
			(layer "F.SilkS")
			(hide yes)
			(effects
				(font
					(size 1.27 1.27)
				)
			)
		)
		(property "Value" ""
			(at 0 0 90)
			(layer "F.Fab")
			(effects
				(font
					(size 1.27 1.27)
				)
			)
		)
		(duplicate_pad_numbers_are_jumpers no)
		(fp_line
			(start 0.7874 -0.4064)
			(end 0.7874 0.4064)
			(stroke
				(width 0.1524)
				(type default)
			)
			(layer "F.SilkS")
		)
		(fp_line
			(start -0.7874 -0.4064)
			(end 0.7874 -0.4064)
			(stroke
				(width 0.1524)
				(type default)
			)
			(layer "F.SilkS")
		)
		(fp_line
			(start 0.7874 0.4064)
			(end -0.7874 0.4064)
			(stroke
				(width 0.1524)
				(type default)
			)
			(layer "F.SilkS")
		)
		(fp_line
			(start -0.7874 0.4064)
			(end -0.7874 -0.4064)
			(stroke
				(width 0.1524)
				(type default)
			)
			(layer "F.SilkS")
		)
		(fp_line
			(start -0.12065 -0.305054)
			(end -0.12065 -0.2794)
			(stroke
				(width 0.1)
				(type default)
			)
			(layer "F.Fab")
		)
		(fp_line
			(start -0.67945 -0.305054)
			(end -0.12065 -0.305054)
			(stroke
				(width 0.1)
				(type default)
			)
			(layer "F.Fab")
		)
		(fp_line
			(start 0.67945 -0.3048)
			(end 0.67945 0.3048)
			(stroke
				(width 0.1)
				(type default)
			)
			(layer "F.Fab")
		)
		(fp_line
			(start 0.12065 -0.3048)
			(end 0.67945 -0.3048)
			(stroke
				(width 0.1)
				(type default)
			)
			(layer "F.Fab")
		)
		(fp_line
			(start 0.12065 -0.2794)
			(end 0.12065 -0.3048)
			(stroke
				(width 0.1)
				(type default)
			)
			(layer "F.Fab")
		)
		(fp_line
			(start -0.12065 -0.2794)
			(end 0.12065 -0.2794)
			(stroke
				(width 0.1)
				(type default)
			)
			(layer "F.Fab")
		)
		(fp_line
			(start 0.120396 0.2794)
			(end -0.12065 0.2794)
			(stroke
				(width 0.1)
				(type default)
			)
			(layer "F.Fab")
		)
		(fp_line
			(start -0.12065 0.2794)
			(end -0.12065 0.3048)
			(stroke
				(width 0.1)
				(type default)
			)
			(layer "F.Fab")
		)
		(fp_line
			(start 0.67945 0.3048)
			(end 0.120396 0.3048)
			(stroke
				(width 0.1)
				(type default)
			)
			(layer "F.Fab")
		)
		(fp_line
			(start 0.120396 0.3048)
			(end 0.120396 0.2794)
			(stroke
				(width 0.1)
				(type default)
			)
			(layer "F.Fab")
		)
		(fp_line
			(start -0.12065 0.3048)
			(end -0.67945 0.3048)
			(stroke
				(width 0.1)
				(type default)
			)
			(layer "F.Fab")
		)
		(fp_line
			(start -0.67945 0.3048)
			(end -0.67945 -0.305054)
			(stroke
				(width 0.1)
				(type default)
			)
			(layer "F.Fab")
		)
		(pad "1" smd circle
			(at -0.40005 0 90)
			(size 0 0)
			(layers "F.Cu" "F.Mask" "F.Paste")
			(net "P3V3_SSD3")
		)
		(pad "2" smd circle
			(at 0.40005 0 90)
			(size 0 0)
			(layers "F.Cu" "F.Mask" "F.Paste")
			(net "SMB_ISO_SSD3_SCL")
		)
	)
	(footprint ""
		(layer "F.Cu")
		(at 106.283252 -212.0392)
		(property "Reference" "PC283"
			(at 0 0 0)
			(layer "F.SilkS")
			(hide yes)
			(effects
				(font
					(size 1.27 1.27)
				)
			)
		)
		(property "Value" ""
			(at 0 0 0)
			(layer "F.Fab")
			(effects
				(font
					(size 1.27 1.27)
				)
			)
		)
		(duplicate_pad_numbers_are_jumpers no)
		(fp_line
			(start -0.7874 -0.4064)
			(end 0.7874 -0.4064)
			(stroke
				(width 0.1524)
				(type default)
			)
			(layer "F.SilkS")
		)
		(fp_line
			(start -0.7874 0.4064)
			(end -0.7874 -0.4064)
			(stroke
				(width 0.1524)
				(type default)
			)
			(layer "F.SilkS")
		)
		(fp_line
			(start 0.7874 -0.4064)
			(end 0.7874 0.4064)
			(stroke
				(width 0.1524)
				(type default)
			)
			(layer "F.SilkS")
		)
		(fp_line
			(start 0.7874 0.4064)
			(end -0.7874 0.4064)
			(stroke
				(width 0.1524)
				(type default)
			)
			(layer "F.SilkS")
		)
		(fp_line
			(start -0.67945 -0.305054)
			(end -0.12065 -0.305054)
			(stroke
				(width 0.1)
				(type default)
			)
			(layer "F.Fab")
		)
		(fp_line
			(start -0.67945 0.3048)
			(end -0.67945 -0.305054)
			(stroke
				(width 0.1)
				(type default)
			)
			(layer "F.Fab")
		)
		(fp_line
			(start -0.12065 -0.305054)
			(end -0.12065 -0.2794)
			(stroke
				(width 0.1)
				(type default)
			)
			(layer "F.Fab")
		)
		(fp_line
			(start -0.12065 -0.2794)
			(end 0.12065 -0.2794)
			(stroke
				(width 0.1)
				(type default)
			)
			(layer "F.Fab")
		)
		(fp_line
			(start -0.12065 0.2794)
			(end -0.12065 0.3048)
			(stroke
				(width 0.1)
				(type default)
			)
			(layer "F.Fab")
		)
		(fp_line
			(start -0.12065 0.3048)
			(end -0.67945 0.3048)
			(stroke
				(width 0.1)
				(type default)
			)
			(layer "F.Fab")
		)
		(fp_line
			(start 0.120396 0.2794)
			(end -0.12065 0.2794)
			(stroke
				(width 0.1)
				(type default)
			)
			(layer "F.Fab")
		)
		(fp_line
			(start 0.120396 0.3048)
			(end 0.120396 0.2794)
			(stroke
				(width 0.1)
				(type default)
			)
			(layer "F.Fab")
		)
		(fp_line
			(start 0.12065 -0.3048)
			(end 0.67945 -0.3048)
			(stroke
				(width 0.1)
				(type default)
			)
			(layer "F.Fab")
		)
		(fp_line
			(start 0.12065 -0.2794)
			(end 0.12065 -0.3048)
			(stroke
				(width 0.1)
				(type default)
			)
			(layer "F.Fab")
		)
		(fp_line
			(start 0.67945 -0.3048)
			(end 0.67945 0.3048)
			(stroke
				(width 0.1)
				(type default)
			)
			(layer "F.Fab")
		)
		(fp_line
			(start 0.67945 0.3048)
			(end 0.120396 0.3048)
			(stroke
				(width 0.1)
				(type default)
			)
			(layer "F.Fab")
		)
		(pad "1" smd circle
			(at -0.40005 0)
			(size 0 0)
			(layers "F.Cu" "F.Mask" "F.Paste")
			(net "P12V_AUX")
		)
		(pad "2" smd circle
			(at 0.40005 0)
			(size 0 0)
			(layers "F.Cu" "F.Mask" "F.Paste")
			(net "GND")
		)
	)
	(footprint ""
		(layer "F.Cu")
		(at 235.056172 -32.848042 -90)
		(property "Reference" "R6078"
			(at 0 0 270)
			(layer "F.SilkS")
			(hide yes)
			(effects
				(font
					(size 1.27 1.27)
				)
			)
		)
		(property "Value" ""
			(at 0 0 270)
			(layer "F.Fab")
			(effects
				(font
					(size 1.27 1.27)
				)
			)
		)
		(duplicate_pad_numbers_are_jumpers no)
		(fp_line
			(start -0.7874 0.4064)
			(end -0.7874 -0.4064)
			(stroke
				(width 0.1524)
				(type default)
			)
			(layer "F.SilkS")
		)
		(fp_line
			(start 0.7874 0.4064)
			(end -0.7874 0.4064)
			(stroke
				(width 0.1524)
				(type default)
			)
			(layer "F.SilkS")
		)
		(fp_line
			(start -0.7874 -0.4064)
			(end 0.7874 -0.4064)
			(stroke
				(width 0.1524)
				(type default)
			)
			(layer "F.SilkS")
		)
		(fp_line
			(start 0.7874 -0.4064)
			(end 0.7874 0.4064)
			(stroke
				(width 0.1524)
				(type default)
			)
			(layer "F.SilkS")
		)
		(fp_line
			(start -0.67945 0.3048)
			(end -0.67945 -0.305054)
			(stroke
				(width 0.1)
				(type default)
			)
			(layer "F.Fab")
		)
		(fp_line
			(start -0.12065 0.3048)
			(end -0.67945 0.3048)
			(stroke
				(width 0.1)
				(type default)
			)
			(layer "F.Fab")
		)
		(fp_line
			(start 0.120396 0.3048)
			(end 0.120396 0.2794)
			(stroke
				(width 0.1)
				(type default)
			)
			(layer "F.Fab")
		)
		(fp_line
			(start 0.67945 0.3048)
			(end 0.120396 0.3048)
			(stroke
				(width 0.1)
				(type default)
			)
			(layer "F.Fab")
		)
		(fp_line
			(start -0.12065 0.2794)
			(end -0.12065 0.3048)
			(stroke
				(width 0.1)
				(type default)
			)
			(layer "F.Fab")
		)
		(fp_line
			(start 0.120396 0.2794)
			(end -0.12065 0.2794)
			(stroke
				(width 0.1)
				(type default)
			)
			(layer "F.Fab")
		)
		(fp_line
			(start -0.12065 -0.2794)
			(end 0.12065 -0.2794)
			(stroke
				(width 0.1)
				(type default)
			)
			(layer "F.Fab")
		)
		(fp_line
			(start 0.12065 -0.2794)
			(end 0.12065 -0.3048)
			(stroke
				(width 0.1)
				(type default)
			)
			(layer "F.Fab")
		)
		(fp_line
			(start 0.12065 -0.3048)
			(end 0.67945 -0.3048)
			(stroke
				(width 0.1)
				(type default)
			)
			(layer "F.Fab")
		)
		(fp_line
			(start 0.67945 -0.3048)
			(end 0.67945 0.3048)
			(stroke
				(width 0.1)
				(type default)
			)
			(layer "F.Fab")
		)
		(fp_line
			(start -0.67945 -0.305054)
			(end -0.12065 -0.305054)
			(stroke
				(width 0.1)
				(type default)
			)
			(layer "F.Fab")
		)
		(fp_line
			(start -0.12065 -0.305054)
			(end -0.12065 -0.2794)
			(stroke
				(width 0.1)
				(type default)
			)
			(layer "F.Fab")
		)
		(pad "1" smd circle
			(at -0.40005 0 270)
			(size 0 0)
			(layers "F.Cu" "F.Mask" "F.Paste")
			(net "SSD8_AUX_P3V3_EN_R")
		)
		(pad "2" smd circle
			(at 0.40005 0 270)
			(size 0 0)
			(layers "F.Cu" "F.Mask" "F.Paste")
			(net "P3V3_SSD8_CO_EN")
		)
	)
	(footprint ""
		(layer "F.Cu")
		(at 479.076512 -527.283426)
		(property "Reference" "J58_12"
			(at -0.5842 -1.31953 0)
			(unlocked yes)
			(layer "B.SilkS")
			(effects
				(font
					(size 0.7874 0.5842)
					(thickness 0.1524)
				)
				(justify left mirror)
			)
		)
		(property "Value" ""
			(at 0 0 0)
			(layer "F.Fab")
			(effects
				(font
					(size 1.27 1.27)
				)
			)
		)
		(duplicate_pad_numbers_are_jumpers no)
		(pad "1" thru_hole circle
			(at 0 0)
			(size 0.4572 0.4572)
			(drill 0.2032)
			(layers "*.Cu" "*.Mask")
			(remove_unused_layers no)
			(net "Net_617")
			(clearance 0.127)
			(thermal_gap 0.127)
			(padstack
				(mode front_inner_back)
				(layer "Inner"
					(shape circle)
					(size 0.4572 0.4572)
					(clearance 0.127)
				)
				(layer "B.Cu"
					(shape circle)
					(size 0.508 0.508)
					(clearance 0.1016)
				)
			)
		)
	)
	(footprint ""
		(layer "F.Cu")
		(at 208.092548 -116.922804)
		(property "Reference" "PC793"
			(at 0 0 0)
			(layer "F.SilkS")
			(hide yes)
			(effects
				(font
					(size 1.27 1.27)
				)
			)
		)
		(property "Value" ""
			(at 0 0 0)
			(layer "F.Fab")
			(effects
				(font
					(size 1.27 1.27)
				)
			)
		)
		(duplicate_pad_numbers_are_jumpers no)
		(fp_line
			(start -1.524 -0.762)
			(end 1.524 -0.762)
			(stroke
				(width 0.1524)
				(type default)
			)
			(layer "F.SilkS")
		)
		(fp_line
			(start -1.524 0.762)
			(end -1.524 -0.762)
			(stroke
				(width 0.1524)
				(type default)
			)
			(layer "F.SilkS")
		)
		(fp_line
			(start 1.524 -0.762)
			(end 1.524 0.762)
			(stroke
				(width 0.1524)
				(type default)
			)
			(layer "F.SilkS")
		)
		(fp_line
			(start 1.524 0.762)
			(end -1.524 0.762)
			(stroke
				(width 0.1524)
				(type default)
			)
			(layer "F.SilkS")
		)
		(fp_line
			(start -1.1049 -0.724916)
			(end -1.1049 0.724916)
			(stroke
				(width 0.1)
				(type default)
			)
			(layer "F.Fab")
		)
		(fp_line
			(start -1.1049 0.724916)
			(end 1.1049 0.724916)
			(stroke
				(width 0.1)
				(type default)
			)
			(layer "F.Fab")
		)
		(fp_line
			(start 1.1049 -0.724916)
			(end -1.1049 -0.724916)
			(stroke
				(width 0.1)
				(type default)
			)
			(layer "F.Fab")
		)
		(fp_line
			(start 1.1049 0.724916)
			(end 1.1049 -0.724916)
			(stroke
				(width 0.1)
				(type default)
			)
			(layer "F.Fab")
		)
		(pad "1" smd rect
			(at -0.889 0 180)
			(size 1.016 1.27)
			(layers "F.Cu" "F.Mask" "F.Paste")
			(net "P3V3_NIC3")
		)
		(pad "2" smd rect
			(at 0.889 0 180)
			(size 1.016 1.27)
			(layers "F.Cu" "F.Mask" "F.Paste")
			(net "GND")
		)
	)
	(footprint ""
		(layer "F.Cu")
		(at 444.118238 -95.31477 90)
		(property "Reference" "R860"
			(at 0 0 90)
			(layer "F.SilkS")
			(hide yes)
			(effects
				(font
					(size 1.27 1.27)
				)
			)
		)
		(property "Value" ""
			(at 0 0 90)
			(layer "F.Fab")
			(effects
				(font
					(size 1.27 1.27)
				)
			)
		)
		(duplicate_pad_numbers_are_jumpers no)
		(fp_line
			(start 0.7874 -0.4064)
			(end 0.7874 0.4064)
			(stroke
				(width 0.1524)
				(type default)
			)
			(layer "F.SilkS")
		)
		(fp_line
			(start -0.7874 -0.4064)
			(end 0.7874 -0.4064)
			(stroke
				(width 0.1524)
				(type default)
			)
			(layer "F.SilkS")
		)
		(fp_line
			(start 0.7874 0.4064)
			(end -0.7874 0.4064)
			(stroke
				(width 0.1524)
				(type default)
			)
			(layer "F.SilkS")
		)
		(fp_line
			(start -0.7874 0.4064)
			(end -0.7874 -0.4064)
			(stroke
				(width 0.1524)
				(type default)
			)
			(layer "F.SilkS")
		)
		(fp_line
			(start -0.12065 -0.305054)
			(end -0.12065 -0.2794)
			(stroke
				(width 0.1)
				(type default)
			)
			(layer "F.Fab")
		)
		(fp_line
			(start -0.67945 -0.305054)
			(end -0.12065 -0.305054)
			(stroke
				(width 0.1)
				(type default)
			)
			(layer "F.Fab")
		)
		(fp_line
			(start 0.67945 -0.3048)
			(end 0.67945 0.3048)
			(stroke
				(width 0.1)
				(type default)
			)
			(layer "F.Fab")
		)
		(fp_line
			(start 0.12065 -0.3048)
			(end 0.67945 -0.3048)
			(stroke
				(width 0.1)
				(type default)
			)
			(layer "F.Fab")
		)
		(fp_line
			(start 0.12065 -0.2794)
			(end 0.12065 -0.3048)
			(stroke
				(width 0.1)
				(type default)
			)
			(layer "F.Fab")
		)
		(fp_line
			(start -0.12065 -0.2794)
			(end 0.12065 -0.2794)
			(stroke
				(width 0.1)
				(type default)
			)
			(layer "F.Fab")
		)
		(fp_line
			(start 0.120396 0.2794)
			(end -0.12065 0.2794)
			(stroke
				(width 0.1)
				(type default)
			)
			(layer "F.Fab")
		)
		(fp_line
			(start -0.12065 0.2794)
			(end -0.12065 0.3048)
			(stroke
				(width 0.1)
				(type default)
			)
			(layer "F.Fab")
		)
		(fp_line
			(start 0.67945 0.3048)
			(end 0.120396 0.3048)
			(stroke
				(width 0.1)
				(type default)
			)
			(layer "F.Fab")
		)
		(fp_line
			(start 0.120396 0.3048)
			(end 0.120396 0.2794)
			(stroke
				(width 0.1)
				(type default)
			)
			(layer "F.Fab")
		)
		(fp_line
			(start -0.12065 0.3048)
			(end -0.67945 0.3048)
			(stroke
				(width 0.1)
				(type default)
			)
			(layer "F.Fab")
		)
		(fp_line
			(start -0.67945 0.3048)
			(end -0.67945 -0.305054)
			(stroke
				(width 0.1)
				(type default)
			)
			(layer "F.Fab")
		)
		(pad "1" smd circle
			(at -0.40005 0 90)
			(size 0 0)
			(layers "F.Cu" "F.Mask" "F.Paste")
			(net "P3V3_AUX")
		)
		(pad "2" smd circle
			(at 0.40005 0 90)
			(size 0 0)
			(layers "F.Cu" "F.Mask" "F.Paste")
			(net "PWRGD_P12V_NIC7")
		)
	)
	(footprint ""
		(layer "F.Cu")
		(at 445.134238 -95.263716 -90)
		(property "Reference" "R4455"
			(at 0 0 270)
			(layer "F.SilkS")
			(hide yes)
			(effects
				(font
					(size 1.27 1.27)
				)
			)
		)
		(property "Value" ""
			(at 0 0 270)
			(layer "F.Fab")
			(effects
				(font
					(size 1.27 1.27)
				)
			)
		)
		(duplicate_pad_numbers_are_jumpers no)
		(fp_line
			(start -0.7874 0.4064)
			(end -0.7874 -0.4064)
			(stroke
				(width 0.1524)
				(type default)
			)
			(layer "F.SilkS")
		)
		(fp_line
			(start 0.7874 0.4064)
			(end -0.7874 0.4064)
			(stroke
				(width 0.1524)
				(type default)
			)
			(layer "F.SilkS")
		)
		(fp_line
			(start -0.7874 -0.4064)
			(end 0.7874 -0.4064)
			(stroke
				(width 0.1524)
				(type default)
			)
			(layer "F.SilkS")
		)
		(fp_line
			(start 0.7874 -0.4064)
			(end 0.7874 0.4064)
			(stroke
				(width 0.1524)
				(type default)
			)
			(layer "F.SilkS")
		)
		(fp_line
			(start -0.67945 0.3048)
			(end -0.67945 -0.305054)
			(stroke
				(width 0.1)
				(type default)
			)
			(layer "F.Fab")
		)
		(fp_line
			(start -0.12065 0.3048)
			(end -0.67945 0.3048)
			(stroke
				(width 0.1)
				(type default)
			)
			(layer "F.Fab")
		)
		(fp_line
			(start 0.120396 0.3048)
			(end 0.120396 0.2794)
			(stroke
				(width 0.1)
				(type default)
			)
			(layer "F.Fab")
		)
		(fp_line
			(start 0.67945 0.3048)
			(end 0.120396 0.3048)
			(stroke
				(width 0.1)
				(type default)
			)
			(layer "F.Fab")
		)
		(fp_line
			(start -0.12065 0.2794)
			(end -0.12065 0.3048)
			(stroke
				(width 0.1)
				(type default)
			)
			(layer "F.Fab")
		)
		(fp_line
			(start 0.120396 0.2794)
			(end -0.12065 0.2794)
			(stroke
				(width 0.1)
				(type default)
			)
			(layer "F.Fab")
		)
		(fp_line
			(start -0.12065 -0.2794)
			(end 0.12065 -0.2794)
			(stroke
				(width 0.1)
				(type default)
			)
			(layer "F.Fab")
		)
		(fp_line
			(start 0.12065 -0.2794)
			(end 0.12065 -0.3048)
			(stroke
				(width 0.1)
				(type default)
			)
			(layer "F.Fab")
		)
		(fp_line
			(start 0.12065 -0.3048)
			(end 0.67945 -0.3048)
			(stroke
				(width 0.1)
				(type default)
			)
			(layer "F.Fab")
		)
		(fp_line
			(start 0.67945 -0.3048)
			(end 0.67945 0.3048)
			(stroke
				(width 0.1)
				(type default)
			)
			(layer "F.Fab")
		)
		(fp_line
			(start -0.67945 -0.305054)
			(end -0.12065 -0.305054)
			(stroke
				(width 0.1)
				(type default)
			)
			(layer "F.Fab")
		)
		(fp_line
			(start -0.12065 -0.305054)
			(end -0.12065 -0.2794)
			(stroke
				(width 0.1)
				(type default)
			)
			(layer "F.Fab")
		)
		(pad "1" smd circle
			(at -0.40005 0 270)
			(size 0 0)
			(layers "F.Cu" "F.Mask" "F.Paste")
			(net "PWRGD_P12V_NIC7")
		)
		(pad "2" smd circle
			(at 0.40005 0 270)
			(size 0 0)
			(layers "F.Cu" "F.Mask" "F.Paste")
			(net "PWRGD_P12V_NIC7_R")
		)
	)
)
